(kicad_pcb
	(version 20260206)
	(generator "pcbnew")
	(generator_version "10.0")
	(general
		(thickness 1.6)
		(legacy_teardrops no)
	)
	(paper "A4")
	(title_block
		(title "01162023_DA0F0TEBIF0_F0T_Expander_BD_F_brd_V02_OCP.brd")
		(comment 1 "Grand Teton / footprints 9669-9675 of 9728")
	)
	(layers
		(0 "F.Cu" signal "TOP")
		(4 "In1.Cu" signal "GND")
		(6 "In2.Cu" signal "VCC")
		(8 "In3.Cu" signal "VCC1")
		(10 "In4.Cu" signal "GND1")
		(12 "In5.Cu" signal "IN1")
		(14 "In6.Cu" signal "GND2")
		(16 "In7.Cu" signal "IN2")
		(18 "In8.Cu" signal "GND3")
		(20 "In9.Cu" signal "IN3")
		(22 "In10.Cu" signal "GND4")
		(24 "In11.Cu" signal "IN4")
		(26 "In12.Cu" signal "GND5")
		(28 "In13.Cu" signal "IN5")
		(30 "In14.Cu" signal "GND6")
		(32 "In15.Cu" signal "IN6")
		(34 "In16.Cu" signal "GND7")
		(2 "B.Cu" signal "BOTTOM")
		(9 "F.Adhes" user "F.Adhesive")
		(11 "B.Adhes" user "B.Adhesive")
		(13 "F.Paste" user "Package Geometry/Pastemask Top")
		(15 "B.Paste" user "Package Geometry/Pastemask Bottom")
		(5 "F.SilkS" user "Ref Des/Silkscreen Top")
		(7 "B.SilkS" user "Ref Des/Silkscreen Bottom")
		(1 "F.Mask" user "Board Geometry/Soldermask Top")
		(3 "B.Mask" user "Board Geometry/Soldermask Bottom")
		(17 "Dwgs.User" user "User.Drawings")
		(19 "Cmts.User" user "User.Comments")
		(21 "Eco1.User" user "User.Eco1")
		(23 "Eco2.User" user "User.Eco2")
		(25 "Edge.Cuts" user "Board Geometry/Outline")
		(27 "Margin" user)
		(31 "F.CrtYd" user "Package Geometry/Place Bound Top")
		(29 "B.CrtYd" user "Package Geometry/Place Bound Bottom")
		(35 "F.Fab" user "Ref Des/Assembly Top")
		(33 "B.Fab" user "Ref Des/Assembly Bottom")
	)
	(footprint ""
		(layer "B.Cu")
		(at 260.259322 -77.959458)
		(property "Reference" "R1046"
			(at 0 0 0)
			(layer "B.SilkS")
			(hide yes)
			(effects
				(font
					(size 1.27 1.27)
				)
				(justify mirror)
			)
		)
		(property "Value" ""
			(at 0 0 0)
			(layer "B.Fab")
			(effects
				(font
					(size 1.27 1.27)
				)
				(justify mirror)
			)
		)
		(duplicate_pad_numbers_are_jumpers no)
		(fp_line
			(start -1.2954 -0.5842)
			(end -1.2954 0.5842)
			(stroke
				(width 0.1524)
				(type default)
			)
			(layer "B.SilkS")
		)
		(fp_line
			(start -1.2954 0.5842)
			(end 1.2954 0.5842)
			(stroke
				(width 0.1524)
				(type default)
			)
			(layer "B.SilkS")
		)
		(fp_line
			(start 1.2954 -0.5842)
			(end -1.2954 -0.5842)
			(stroke
				(width 0.1524)
				(type default)
			)
			(layer "B.SilkS")
		)
		(fp_line
			(start 1.2954 0.5842)
			(end 1.2954 -0.5842)
			(stroke
				(width 0.1524)
				(type default)
			)
			(layer "B.SilkS")
		)
		(fp_line
			(start -1.1938 -0.406654)
			(end -1.1938 0.4064)
			(stroke
				(width 0.1)
				(type default)
			)
			(layer "B.Fab")
		)
		(fp_line
			(start -1.1938 0.4064)
			(end -0.8636 0.4064)
			(stroke
				(width 0.1)
				(type default)
			)
			(layer "B.Fab")
		)
		(fp_line
			(start -0.8636 -0.4572)
			(end -0.8636 -0.406654)
			(stroke
				(width 0.1)
				(type default)
			)
			(layer "B.Fab")
		)
		(fp_line
			(start -0.8636 -0.406654)
			(end -1.1938 -0.406654)
			(stroke
				(width 0.1)
				(type default)
			)
			(layer "B.Fab")
		)
		(fp_line
			(start -0.8636 0.4064)
			(end -0.8636 0.4572)
			(stroke
				(width 0.1)
				(type default)
			)
			(layer "B.Fab")
		)
		(fp_line
			(start -0.8636 0.4572)
			(end 0.8636 0.4572)
			(stroke
				(width 0.1)
				(type default)
			)
			(layer "B.Fab")
		)
		(fp_line
			(start 0.8636 -0.4572)
			(end -0.8636 -0.4572)
			(stroke
				(width 0.1)
				(type default)
			)
			(layer "B.Fab")
		)
		(fp_line
			(start 0.8636 -0.406654)
			(end 0.8636 -0.4572)
			(stroke
				(width 0.1)
				(type default)
			)
			(layer "B.Fab")
		)
		(fp_line
			(start 0.8636 0.4064)
			(end 1.1938 0.4064)
			(stroke
				(width 0.1)
				(type default)
			)
			(layer "B.Fab")
		)
		(fp_line
			(start 0.8636 0.4318)
			(end 0.8636 0.4064)
			(stroke
				(width 0.1)
				(type default)
			)
			(layer "B.Fab")
		)
		(fp_line
			(start 0.8636 0.4572)
			(end 0.8636 0.4318)
			(stroke
				(width 0.1)
				(type default)
			)
			(layer "B.Fab")
		)
		(fp_line
			(start 1.1938 -0.406654)
			(end 0.8636 -0.406654)
			(stroke
				(width 0.1)
				(type default)
			)
			(layer "B.Fab")
		)
		(fp_line
			(start 1.1938 0.4064)
			(end 1.1938 -0.406654)
			(stroke
				(width 0.1)
				(type default)
			)
			(layer "B.Fab")
		)
		(pad "1" smd rect
			(at 0.7366 0 270)
			(size 0.7112 0.8128)
			(layers "B.Cu" "B.Mask" "B.Paste")
			(net "P3V3_CLK_GEN_VDD_CK440")
		)
		(pad "2" smd rect
			(at -0.7366 0 270)
			(size 0.7112 0.8128)
			(layers "B.Cu" "B.Mask" "B.Paste")
			(net "P3V3_CLK_GEN_VDDA100M_CK440")
		)
	)
	(footprint ""
		(layer "B.Cu")
		(at 402.249894 -288.299906 90)
		(property "Reference" "C3451"
			(at 0 0 90)
			(layer "B.SilkS")
			(hide yes)
			(effects
				(font
					(size 1.27 1.27)
				)
				(justify mirror)
			)
		)
		(property "Value" ""
			(at 0 0 90)
			(layer "B.Fab")
			(effects
				(font
					(size 1.27 1.27)
				)
				(justify mirror)
			)
		)
		(duplicate_pad_numbers_are_jumpers no)
		(fp_line
			(start 0.299974 -0.150114)
			(end -0.299974 -0.150114)
			(stroke
				(width 0.1)
				(type default)
			)
			(layer "B.Fab")
		)
		(fp_line
			(start -0.299974 -0.150114)
			(end -0.299974 0.150114)
			(stroke
				(width 0.1)
				(type default)
			)
			(layer "B.Fab")
		)
		(fp_line
			(start 0.299974 0.150114)
			(end 0.299974 -0.150114)
			(stroke
				(width 0.1)
				(type default)
			)
			(layer "B.Fab")
		)
		(fp_line
			(start -0.299974 0.150114)
			(end 0.299974 0.150114)
			(stroke
				(width 0.1)
				(type default)
			)
			(layer "B.Fab")
		)
		(pad "1" smd rect
			(at 0.2667 0 270)
			(size 0.3048 0.381)
			(layers "B.Cu" "B.Mask" "B.Paste")
			(net "P1V25_PEX3")
		)
		(pad "2" smd rect
			(at -0.2667 0 270)
			(size 0.3048 0.381)
			(layers "B.Cu" "B.Mask" "B.Paste")
			(net "GND")
		)
	)
	(footprint ""
		(layer "B.Cu")
		(at 106.57078 -84.968842 180)
		(property "Reference" "C2666"
			(at 0 0 0)
			(layer "B.SilkS")
			(hide yes)
			(effects
				(font
					(size 1.27 1.27)
				)
				(justify mirror)
			)
		)
		(property "Value" ""
			(at 0 0 0)
			(layer "B.Fab")
			(effects
				(font
					(size 1.27 1.27)
				)
				(justify mirror)
			)
		)
		(duplicate_pad_numbers_are_jumpers no)
		(fp_line
			(start 0.7874 0.4064)
			(end 0.7874 -0.4064)
			(stroke
				(width 0.1524)
				(type default)
			)
			(layer "B.SilkS")
		)
		(fp_line
			(start 0.7874 -0.4064)
			(end -0.7874 -0.4064)
			(stroke
				(width 0.1524)
				(type default)
			)
			(layer "B.SilkS")
		)
		(fp_line
			(start -0.7874 0.4064)
			(end 0.7874 0.4064)
			(stroke
				(width 0.1524)
				(type default)
			)
			(layer "B.SilkS")
		)
		(fp_line
			(start -0.7874 -0.4064)
			(end -0.7874 0.4064)
			(stroke
				(width 0.1524)
				(type default)
			)
			(layer "B.SilkS")
		)
		(fp_line
			(start 0.67945 0.3048)
			(end 0.67945 -0.305054)
			(stroke
				(width 0.1)
				(type default)
			)
			(layer "B.Fab")
		)
		(fp_line
			(start 0.67945 -0.305054)
			(end 0.12065 -0.305054)
			(stroke
				(width 0.1)
				(type default)
			)
			(layer "B.Fab")
		)
		(fp_line
			(start 0.12065 0.3048)
			(end 0.67945 0.3048)
			(stroke
				(width 0.1)
				(type default)
			)
			(layer "B.Fab")
		)
		(fp_line
			(start 0.12065 0.2794)
			(end 0.12065 0.3048)
			(stroke
				(width 0.1)
				(type default)
			)
			(layer "B.Fab")
		)
		(fp_line
			(start 0.12065 -0.2794)
			(end -0.12065 -0.2794)
			(stroke
				(width 0.1)
				(type default)
			)
			(layer "B.Fab")
		)
		(fp_line
			(start 0.12065 -0.305054)
			(end 0.12065 -0.2794)
			(stroke
				(width 0.1)
				(type default)
			)
			(layer "B.Fab")
		)
		(fp_line
			(start -0.120396 0.3048)
			(end -0.120396 0.2794)
			(stroke
				(width 0.1)
				(type default)
			)
			(layer "B.Fab")
		)
		(fp_line
			(start -0.120396 0.2794)
			(end 0.12065 0.2794)
			(stroke
				(width 0.1)
				(type default)
			)
			(layer "B.Fab")
		)
		(fp_line
			(start -0.12065 -0.2794)
			(end -0.12065 -0.3048)
			(stroke
				(width 0.1)
				(type default)
			)
			(layer "B.Fab")
		)
		(fp_line
			(start -0.12065 -0.3048)
			(end -0.67945 -0.3048)
			(stroke
				(width 0.1)
				(type default)
			)
			(layer "B.Fab")
		)
		(fp_line
			(start -0.67945 0.3048)
			(end -0.120396 0.3048)
			(stroke
				(width 0.1)
				(type default)
			)
			(layer "B.Fab")
		)
		(fp_line
			(start -0.67945 -0.3048)
			(end -0.67945 0.3048)
			(stroke
				(width 0.1)
				(type default)
			)
			(layer "B.Fab")
		)
		(pad "1" smd circle
			(at 0.40005 0)
			(size 0 0)
			(layers "B.Cu" "B.Mask" "B.Paste")
			(net "P3V3_VDD_9ZXL0851_0_7")
		)
		(pad "2" smd circle
			(at -0.40005 0)
			(size 0 0)
			(layers "B.Cu" "B.Mask" "B.Paste")
			(net "GND")
		)
	)
	(footprint ""
		(layer "B.Cu")
		(at 340.494112 -218.787218 -90)
		(property "Reference" "C2064"
			(at 0 0 90)
			(layer "B.SilkS")
			(hide yes)
			(effects
				(font
					(size 1.27 1.27)
				)
				(justify mirror)
			)
		)
		(property "Value" ""
			(at 0 0 90)
			(layer "B.Fab")
			(effects
				(font
					(size 1.27 1.27)
				)
				(justify mirror)
			)
		)
		(duplicate_pad_numbers_are_jumpers no)
		(fp_line
			(start -0.69215 0.2921)
			(end 0.69215 0.2921)
			(stroke
				(width 0.1524)
				(type default)
			)
			(layer "B.SilkS")
		)
		(fp_line
			(start 0.69215 0.2921)
			(end 0.69215 -0.2921)
			(stroke
				(width 0.1524)
				(type default)
			)
			(layer "B.SilkS")
		)
		(fp_line
			(start -0.69215 -0.2921)
			(end -0.69215 0.2921)
			(stroke
				(width 0.1524)
				(type default)
			)
			(layer "B.SilkS")
		)
		(fp_line
			(start 0.69215 -0.2921)
			(end -0.69215 -0.2921)
			(stroke
				(width 0.1524)
				(type default)
			)
			(layer "B.SilkS")
		)
		(fp_line
			(start -0.51435 0.2794)
			(end 0.51435 0.2794)
			(stroke
				(width 0.1)
				(type default)
			)
			(layer "B.Fab")
		)
		(fp_line
			(start 0.51435 0.2794)
			(end 0.51435 -0.2794)
			(stroke
				(width 0.1)
				(type default)
			)
			(layer "B.Fab")
		)
		(fp_line
			(start -0.51435 -0.2794)
			(end -0.51435 0.2794)
			(stroke
				(width 0.1)
				(type default)
			)
			(layer "B.Fab")
		)
		(fp_line
			(start 0.51435 -0.2794)
			(end -0.51435 -0.2794)
			(stroke
				(width 0.1)
				(type default)
			)
			(layer "B.Fab")
		)
		(pad "1" smd circle
			(at 0.40005 0 90)
			(size 0 0)
			(layers "B.Cu" "B.Mask" "B.Paste")
			(net "P3V3_VCC_FPGA_CORE")
		)
		(pad "2" smd circle
			(at -0.40005 0 90)
			(size 0 0)
			(layers "B.Cu" "B.Mask" "B.Paste")
			(net "GND")
		)
		(zone
			(layer "B.Cu")
			(hatch none 0.5)
			(connect_pads
				(clearance 0)
			)
			(min_thickness 0.25)
			(keepout
				(tracks not_allowed)
				(vias allowed)
				(pads allowed)
				(copperpour not_allowed)
				(footprints allowed)
			)
			(placement
				(enabled no)
				(sheetname "")
			)
			(fill
				(thermal_gap 0.5)
				(thermal_bridge_width 0.5)
				(island_removal_mode 0)
			)
			(polygon
				(pts
					(xy 340.406482 -218.596718) (xy 340.348316 -218.688158) (xy 340.348316 -218.887548) (xy 340.406482 -218.977718)
					(xy 340.581742 -218.977718) (xy 340.640162 -218.887548) (xy 340.640162 -218.688158) (xy 340.581996 -218.596718)
				)
			)
		)
	)
	(footprint ""
		(layer "B.Cu")
		(at 130.906774 -174.596044 90)
		(property "Reference" "C2661"
			(at 0 0 90)
			(layer "B.SilkS")
			(hide yes)
			(effects
				(font
					(size 1.27 1.27)
				)
				(justify mirror)
			)
		)
		(property "Value" ""
			(at 0 0 90)
			(layer "B.Fab")
			(effects
				(font
					(size 1.27 1.27)
				)
				(justify mirror)
			)
		)
		(duplicate_pad_numbers_are_jumpers no)
		(fp_line
			(start 0.7874 -0.4064)
			(end -0.7874 -0.4064)
			(stroke
				(width 0.1524)
				(type default)
			)
			(layer "B.SilkS")
		)
		(fp_line
			(start -0.7874 -0.4064)
			(end -0.7874 0.4064)
			(stroke
				(width 0.1524)
				(type default)
			)
			(layer "B.SilkS")
		)
		(fp_line
			(start 0.7874 0.4064)
			(end 0.7874 -0.4064)
			(stroke
				(width 0.1524)
				(type default)
			)
			(layer "B.SilkS")
		)
		(fp_line
			(start -0.7874 0.4064)
			(end 0.7874 0.4064)
			(stroke
				(width 0.1524)
				(type default)
			)
			(layer "B.SilkS")
		)
		(fp_line
			(start 0.67945 -0.305054)
			(end 0.12065 -0.305054)
			(stroke
				(width 0.1)
				(type default)
			)
			(layer "B.Fab")
		)
		(fp_line
			(start 0.12065 -0.305054)
			(end 0.12065 -0.2794)
			(stroke
				(width 0.1)
				(type default)
			)
			(layer "B.Fab")
		)
		(fp_line
			(start -0.12065 -0.3048)
			(end -0.67945 -0.3048)
			(stroke
				(width 0.1)
				(type default)
			)
			(layer "B.Fab")
		)
		(fp_line
			(start -0.67945 -0.3048)
			(end -0.67945 0.3048)
			(stroke
				(width 0.1)
				(type default)
			)
			(layer "B.Fab")
		)
		(fp_line
			(start 0.12065 -0.2794)
			(end -0.12065 -0.2794)
			(stroke
				(width 0.1)
				(type default)
			)
			(layer "B.Fab")
		)
		(fp_line
			(start -0.12065 -0.2794)
			(end -0.12065 -0.3048)
			(stroke
				(width 0.1)
				(type default)
			)
			(layer "B.Fab")
		)
		(fp_line
			(start 0.12065 0.2794)
			(end 0.12065 0.3048)
			(stroke
				(width 0.1)
				(type default)
			)
			(layer "B.Fab")
		)
		(fp_line
			(start -0.120396 0.2794)
			(end 0.12065 0.2794)
			(stroke
				(width 0.1)
				(type default)
			)
			(layer "B.Fab")
		)
		(fp_line
			(start 0.67945 0.3048)
			(end 0.67945 -0.305054)
			(stroke
				(width 0.1)
				(type default)
			)
			(layer "B.Fab")
		)
		(fp_line
			(start 0.12065 0.3048)
			(end 0.67945 0.3048)
			(stroke
				(width 0.1)
				(type default)
			)
			(layer "B.Fab")
		)
		(fp_line
			(start -0.120396 0.3048)
			(end -0.120396 0.2794)
			(stroke
				(width 0.1)
				(type default)
			)
			(layer "B.Fab")
		)
		(fp_line
			(start -0.67945 0.3048)
			(end -0.120396 0.3048)
			(stroke
				(width 0.1)
				(type default)
			)
			(layer "B.Fab")
		)
		(pad "1" smd circle
			(at 0.40005 0 270)
			(size 0 0)
			(layers "B.Cu" "B.Mask" "B.Paste")
			(net "P3V3_DB2000QL_VDD")
		)
		(pad "2" smd circle
			(at -0.40005 0 270)
			(size 0 0)
			(layers "B.Cu" "B.Mask" "B.Paste")
			(net "GND")
		)
	)
	(footprint ""
		(layer "B.Cu")
		(at 213.813136 -221.350586)
		(property "Reference" "R4883"
			(at 0 0 0)
			(layer "B.SilkS")
			(hide yes)
			(effects
				(font
					(size 1.27 1.27)
				)
				(justify mirror)
			)
		)
		(property "Value" ""
			(at 0 0 0)
			(layer "B.Fab")
			(effects
				(font
					(size 1.27 1.27)
				)
				(justify mirror)
			)
		)
		(duplicate_pad_numbers_are_jumpers no)
		(fp_line
			(start -0.7874 -0.4064)
			(end -0.7874 0.4064)
			(stroke
				(width 0.1524)
				(type default)
			)
			(layer "B.SilkS")
		)
		(fp_line
			(start -0.7874 0.4064)
			(end 0.7874 0.4064)
			(stroke
				(width 0.1524)
				(type default)
			)
			(layer "B.SilkS")
		)
		(fp_line
			(start 0.7874 -0.4064)
			(end -0.7874 -0.4064)
			(stroke
				(width 0.1524)
				(type default)
			)
			(layer "B.SilkS")
		)
		(fp_line
			(start 0.7874 0.4064)
			(end 0.7874 -0.4064)
			(stroke
				(width 0.1524)
				(type default)
			)
			(layer "B.SilkS")
		)
		(fp_line
			(start -0.67945 -0.3048)
			(end -0.67945 0.3048)
			(stroke
				(width 0.1)
				(type default)
			)
			(layer "B.Fab")
		)
		(fp_line
			(start -0.67945 0.3048)
			(end -0.120396 0.3048)
			(stroke
				(width 0.1)
				(type default)
			)
			(layer "B.Fab")
		)
		(fp_line
			(start -0.12065 -0.3048)
			(end -0.67945 -0.3048)
			(stroke
				(width 0.1)
				(type default)
			)
			(layer "B.Fab")
		)
		(fp_line
			(start -0.12065 -0.2794)
			(end -0.12065 -0.3048)
			(stroke
				(width 0.1)
				(type default)
			)
			(layer "B.Fab")
		)
		(fp_line
			(start -0.120396 0.2794)
			(end 0.12065 0.2794)
			(stroke
				(width 0.1)
				(type default)
			)
			(layer "B.Fab")
		)
		(fp_line
			(start -0.120396 0.3048)
			(end -0.120396 0.2794)
			(stroke
				(width 0.1)
				(type default)
			)
			(layer "B.Fab")
		)
		(fp_line
			(start 0.12065 -0.305054)
			(end 0.12065 -0.2794)
			(stroke
				(width 0.1)
				(type default)
			)
			(layer "B.Fab")
		)
		(fp_line
			(start 0.12065 -0.2794)
			(end -0.12065 -0.2794)
			(stroke
				(width 0.1)
				(type default)
			)
			(layer "B.Fab")
		)
		(fp_line
			(start 0.12065 0.2794)
			(end 0.12065 0.3048)
			(stroke
				(width 0.1)
				(type default)
			)
			(layer "B.Fab")
		)
		(fp_line
			(start 0.12065 0.3048)
			(end 0.67945 0.3048)
			(stroke
				(width 0.1)
				(type default)
			)
			(layer "B.Fab")
		)
		(fp_line
			(start 0.67945 -0.305054)
			(end 0.12065 -0.305054)
			(stroke
				(width 0.1)
				(type default)
			)
			(layer "B.Fab")
		)
		(fp_line
			(start 0.67945 0.3048)
			(end 0.67945 -0.305054)
			(stroke
				(width 0.1)
				(type default)
			)
			(layer "B.Fab")
		)
		(pad "1" smd circle
			(at 0.40005 0 180)
			(size 0 0)
			(layers "B.Cu" "B.Mask" "B.Paste")
			(net "SMB_BIC_FPGA_R_SCL")
		)
		(pad "2" smd circle
			(at -0.40005 0 180)
			(size 0 0)
			(layers "B.Cu" "B.Mask" "B.Paste")
			(net "P3V3_AUX")
		)
	)
	(footprint ""
		(layer "B.Cu")
		(at 339.979 -233.553 -90)
		(property "Reference" "R3599"
			(at 0 0 90)
			(layer "B.SilkS")
			(hide yes)
			(effects
				(font
					(size 1.27 1.27)
				)
				(justify mirror)
			)
		)
		(property "Value" ""
			(at 0 0 90)
			(layer "B.Fab")
			(effects
				(font
					(size 1.27 1.27)
				)
				(justify mirror)
			)
		)
		(duplicate_pad_numbers_are_jumpers no)
		(fp_line
			(start -0.7874 0.4064)
			(end 0.7874 0.4064)
			(stroke
				(width 0.1524)
				(type default)
			)
			(layer "B.SilkS")
		)
		(fp_line
			(start 0.7874 0.4064)
			(end 0.7874 -0.4064)
			(stroke
				(width 0.1524)
				(type default)
			)
			(layer "B.SilkS")
		)
		(fp_line
			(start -0.7874 -0.4064)
			(end -0.7874 0.4064)
			(stroke
				(width 0.1524)
				(type default)
			)
			(layer "B.SilkS")
		)
		(fp_line
			(start 0.7874 -0.4064)
			(end -0.7874 -0.4064)
			(stroke
				(width 0.1524)
				(type default)
			)
			(layer "B.SilkS")
		)
		(fp_line
			(start -0.67945 0.3048)
			(end -0.120396 0.3048)
			(stroke
				(width 0.1)
				(type default)
			)
			(layer "B.Fab")
		)
		(fp_line
			(start -0.120396 0.3048)
			(end -0.120396 0.2794)
			(stroke
				(width 0.1)
				(type default)
			)
			(layer "B.Fab")
		)
		(fp_line
			(start 0.12065 0.3048)
			(end 0.67945 0.3048)
			(stroke
				(width 0.1)
				(type default)
			)
			(layer "B.Fab")
		)
		(fp_line
			(start 0.67945 0.3048)
			(end 0.67945 -0.305054)
			(stroke
				(width 0.1)
				(type default)
			)
			(layer "B.Fab")
		)
		(fp_line
			(start -0.120396 0.2794)
			(end 0.12065 0.2794)
			(stroke
				(width 0.1)
				(type default)
			)
			(layer "B.Fab")
		)
		(fp_line
			(start 0.12065 0.2794)
			(end 0.12065 0.3048)
			(stroke
				(width 0.1)
				(type default)
			)
			(layer "B.Fab")
		)
		(fp_line
			(start -0.12065 -0.2794)
			(end -0.12065 -0.3048)
			(stroke
				(width 0.1)
				(type default)
			)
			(layer "B.Fab")
		)
		(fp_line
			(start 0.12065 -0.2794)
			(end -0.12065 -0.2794)
			(stroke
				(width 0.1)
				(type default)
			)
			(layer "B.Fab")
		)
		(fp_line
			(start -0.67945 -0.3048)
			(end -0.67945 0.3048)
			(stroke
				(width 0.1)
				(type default)
			)
			(layer "B.Fab")
		)
		(fp_line
			(start -0.12065 -0.3048)
			(end -0.67945 -0.3048)
			(stroke
				(width 0.1)
				(type default)
			)
			(layer "B.Fab")
		)
		(fp_line
			(start 0.12065 -0.305054)
			(end 0.12065 -0.2794)
			(stroke
				(width 0.1)
				(type default)
			)
			(layer "B.Fab")
		)
		(fp_line
			(start 0.67945 -0.305054)
			(end 0.12065 -0.305054)
			(stroke
				(width 0.1)
				(type default)
			)
			(layer "B.Fab")
		)
		(pad "1" smd circle
			(at 0.40005 0 90)
			(size 0 0)
			(layers "B.Cu" "B.Mask" "B.Paste")
			(net "SSD1_CLK_EN_N")
		)
		(pad "2" smd circle
			(at -0.40005 0 90)
			(size 0 0)
			(layers "B.Cu" "B.Mask" "B.Paste")
			(net "SSD1_CLK_EN_R_N")
		)
	)
)
